# T6G (Grand Teton) — schematic netlist excerpt (pin names and nets, part order shuffled) for the footprints in the layout excerpt that follows; sources: Cadence DE-HDL packaged netlist, KiCad conversion of 04192023_DAF0TMB3IC0_F0TG_MB_C_brd_V02_OCP.brd

R2724  Q_RES  0 5% EMPTY  pkg 0402LF  page 248 : A = SMB_BMC_SWB_R_SDA ; B = SMB_BMC_SWB_BUF_R_SDA

(kicad_pcb
	(version 20260206)
	(generator "pcbnew")
	(generator_version "10.0")
	(general
		(thickness 1.6)
		(legacy_teardrops no)
	)
	(paper "A4")
	(title_block
		(title "04192023_DAF0TMB3IC0_F0TG_MB_C_brd_V02_OCP.brd")
		(comment 1 "Grand Teton / footprints 4370-4370 of 8354")
	)
	(layers
		(0 "F.Cu" signal "TOP")
		(4 "In1.Cu" signal "GND")
		(6 "In2.Cu" signal "IN1")
		(8 "In3.Cu" signal "GND1")
		(10 "In4.Cu" signal "IN2")
		(12 "In5.Cu" signal "GND2")
		(14 "In6.Cu" signal "IN3")
		(16 "In7.Cu" signal "GND3")
		(18 "In8.Cu" signal "VCC")
		(20 "In9.Cu" signal "VCC1")
		(22 "In10.Cu" signal "GND4")
		(24 "In11.Cu" signal "IN4")
		(26 "In12.Cu" signal "GND5")
		(28 "In13.Cu" signal "IN5")
		(30 "In14.Cu" signal "GND6")
		(32 "In15.Cu" signal "IN6")
		(34 "In16.Cu" signal "GND7")
		(2 "B.Cu" signal "BOTTOM")
		(9 "F.Adhes" user "F.Adhesive")
		(11 "B.Adhes" user "B.Adhesive")
		(13 "F.Paste" user "Package Geometry/Pastemask Top")
		(15 "B.Paste" user "Package Geometry/Pastemask Bottom")
		(5 "F.SilkS" user "Ref Des/Silkscreen Top")
		(7 "B.SilkS" user "Ref Des/Silkscreen Bottom")
		(1 "F.Mask" user "Board Geometry/Soldermask Top")
		(3 "B.Mask" user "Board Geometry/Soldermask Bottom")
		(17 "Dwgs.User" user "User.Drawings")
		(19 "Cmts.User" user "User.Comments")
		(21 "Eco1.User" user "User.Eco1")
		(23 "Eco2.User" user "User.Eco2")
		(25 "Edge.Cuts" user "Board Geometry/Outline")
		(27 "Margin" user)
		(31 "F.CrtYd" user "Package Geometry/Place Bound Top")
		(29 "B.CrtYd" user "Package Geometry/Place Bound Bottom")
		(35 "F.Fab" user "Ref Des/Assembly Top")
		(33 "B.Fab" user "Ref Des/Assembly Bottom")
	)
	(footprint ""
		(layer "F.Cu")
		(at 166.3192 -434.869336)
		(property "Reference" "R2724"
			(at 0 0 0)
			(layer "F.SilkS")
			(hide yes)
			(effects
				(font
					(size 1.27 1.27)
				)
			)
		)
		(property "Value" ""
			(at 0 0 0)
			(layer "F.Fab")
			(effects
				(font
					(size 1.27 1.27)
				)
			)
		)
		(duplicate_pad_numbers_are_jumpers no)
		(fp_line
			(start -0.7874 -0.4064)
			(end 0.7874 -0.4064)
			(stroke
				(width 0.1524)
				(type default)
			)
			(layer "F.SilkS")
		)
		(fp_line
			(start -0.7874 0.4064)
			(end -0.7874 -0.4064)
			(stroke
				(width 0.1524)
				(type default)
			)
			(layer "F.SilkS")
		)
		(fp_line
			(start 0.7874 -0.4064)
			(end 0.7874 0.4064)
			(stroke
				(width 0.1524)
				(type default)
			)
			(layer "F.SilkS")
		)
		(fp_line
			(start 0.7874 0.4064)
			(end -0.7874 0.4064)
			(stroke
				(width 0.1524)
				(type default)
			)
			(layer "F.SilkS")
		)
		(fp_line
			(start -0.67945 -0.305054)
			(end -0.12065 -0.305054)
			(stroke
				(width 0.1)
				(type default)
			)
			(layer "F.Fab")
		)
		(fp_line
			(start -0.67945 0.3048)
			(end -0.67945 -0.305054)
			(stroke
				(width 0.1)
				(type default)
			)
			(layer "F.Fab")
		)
		(fp_line
			(start -0.12065 -0.305054)
			(end -0.12065 -0.2794)
			(stroke
				(width 0.1)
				(type default)
			)
			(layer "F.Fab")
		)
		(fp_line
			(start -0.12065 -0.2794)
			(end 0.12065 -0.2794)
			(stroke
				(width 0.1)
				(type default)
			)
			(layer "F.Fab")
		)
		(fp_line
			(start -0.12065 0.2794)
			(end -0.12065 0.3048)
			(stroke
				(width 0.1)
				(type default)
			)
			(layer "F.Fab")
		)
		(fp_line
			(start -0.12065 0.3048)
			(end -0.67945 0.3048)
			(stroke
				(width 0.1)
				(type default)
			)
			(layer "F.Fab")
		)
		(fp_line
			(start 0.120396 0.2794)
			(end -0.12065 0.2794)
			(stroke
				(width 0.1)
				(type default)
			)
			(layer "F.Fab")
		)
		(fp_line
			(start 0.120396 0.3048)
			(end 0.120396 0.2794)
			(stroke
				(width 0.1)
				(type default)
			)
			(layer "F.Fab")
		)
		(fp_line
			(start 0.12065 -0.3048)
			(end 0.67945 -0.3048)
			(stroke
				(width 0.1)
				(type default)
			)
			(layer "F.Fab")
		)
		(fp_line
			(start 0.12065 -0.2794)
			(end 0.12065 -0.3048)
			(stroke
				(width 0.1)
				(type default)
			)
			(layer "F.Fab")
		)
		(fp_line
			(start 0.67945 -0.3048)
			(end 0.67945 0.3048)
			(stroke
				(width 0.1)
				(type default)
			)
			(layer "F.Fab")
		)
		(fp_line
			(start 0.67945 0.3048)
			(end 0.120396 0.3048)
			(stroke
				(width 0.1)
				(type default)
			)
			(layer "F.Fab")
		)
		(pad "1" smd circle
			(at -0.40005 0)
			(size 0 0)
			(layers "F.Cu" "F.Mask" "F.Paste")
			(net "SMB_BMC_SWB_R_SDA")
		)
		(pad "2" smd circle
			(at 0.40005 0)
			(size 0 0)
			(layers "F.Cu" "F.Mask" "F.Paste")
			(net "SMB_BMC_SWB_BUF_R_SDA")
		)
	)
)
